(kicad_pcb
	(version 20241229)
	(generator "pcbnew")
	(generator_version "9.0")
	(general
		(thickness 1.61)
		(legacy_teardrops no)
	)
	(paper "A3")
	(title_block
		(title "RDIMM DDR5 Tester")
		(date "2026-05-21")
		(rev "2.2.0")
		(company "Antmicro")
		(comment 9 "footprints 199-203 of 796")
	)
	(layers
		(0 "F.Cu" signal)
		(4 "In1.Cu" power)
		(6 "In2.Cu" mixed)
		(8 "In3.Cu" power)
		(10 "In4.Cu" mixed)
		(12 "In5.Cu" power)
		(14 "In6.Cu" mixed)
		(16 "In7.Cu" power)
		(18 "In8.Cu" power)
		(20 "In9.Cu" mixed)
		(22 "In10.Cu" power)
		(2 "B.Cu" signal)
		(9 "F.Adhes" user "F.Adhesive")
		(11 "B.Adhes" user "B.Adhesive")
		(13 "F.Paste" user)
		(15 "B.Paste" user)
		(5 "F.SilkS" user "F.Silkscreen")
		(7 "B.SilkS" user "B.Silkscreen")
		(1 "F.Mask" user)
		(3 "B.Mask" user)
		(17 "Dwgs.User" user "User.Drawings")
		(19 "Cmts.User" user "User.Comments")
		(21 "Eco1.User" user "User.Eco1")
		(23 "Eco2.User" user "User.Eco2")
		(25 "Edge.Cuts" user)
		(27 "Margin" user)
		(31 "F.CrtYd" user "F.Courtyard")
		(29 "B.CrtYd" user "B.Courtyard")
		(35 "F.Fab" user)
		(33 "B.Fab" user)
	)
	(footprint "antmicro-footprints:C_0402_1005Metric"
		(layer "F.Cu")
		(at 120.941 186.1375 180)
		(descr "Capacitor SMD 0402")
		(tags "capacitor SMD 0402")
		(property "Reference" "C282"
			(at -1.039 -1.4425 0)
			(layer "F.SilkS")
			(effects
				(font
					(size 0.7 0.7)
					(thickness 0.15)
				)
				(justify right bottom)
			)
		)
		(property "Value" "C_100n_0402"
			(at -1.022927 2.155213 0)
			(layer "F.Fab")
			(effects
				(font
					(size 0.7 0.7)
					(thickness 0.15)
				)
				(justify right bottom)
			)
		)
		(property "Datasheet" "https://www.murata.com/products/productdetail?partno=GRM155R61H104KE14%23"
			(at 0 0 180)
			(layer "F.Fab")
			(hide yes)
			(effects
				(font
					(size 1.27 1.27)
					(thickness 0.15)
				)
			)
		)
		(property "MPN" "GRM155R61H104KE14D"
			(at 0 0 180)
			(unlocked yes)
			(layer "F.Fab")
			(hide yes)
			(effects
				(font
					(size 1 1)
					(thickness 0.15)
				)
			)
		)
		(property "Manufacturer" "Murata"
			(at 0 0 180)
			(unlocked yes)
			(layer "F.Fab")
			(hide yes)
			(effects
				(font
					(size 1 1)
					(thickness 0.15)
				)
			)
		)
		(property "License" "Apache-2.0"
			(at 0 0 180)
			(unlocked yes)
			(layer "F.Fab")
			(hide yes)
			(effects
				(font
					(size 1 1)
					(thickness 0.15)
				)
			)
		)
		(property "Author" "Antmicro"
			(at 0 0 180)
			(unlocked yes)
			(layer "F.Fab")
			(hide yes)
			(effects
				(font
					(size 1 1)
					(thickness 0.15)
				)
			)
		)
		(property "Val" "100n"
			(at 0 0 180)
			(unlocked yes)
			(layer "F.Fab")
			(hide yes)
			(effects
				(font
					(size 1 1)
					(thickness 0.15)
				)
			)
		)
		(property "Voltage" "50V"
			(at 0 0 180)
			(unlocked yes)
			(layer "F.Fab")
			(hide yes)
			(effects
				(font
					(size 1 1)
					(thickness 0.15)
				)
			)
		)
		(property "Dielectric" "X5R"
			(at 0 0 180)
			(unlocked yes)
			(layer "F.Fab")
			(hide yes)
			(effects
				(font
					(size 1 1)
					(thickness 0.15)
				)
			)
		)
		(property "Public" ""
			(at 0 0 180)
			(unlocked yes)
			(layer "F.Fab")
			(hide yes)
			(effects
				(font
					(size 1 1)
					(thickness 0.15)
				)
			)
		)
		(sheetname "/HDMI + SD Card/")
		(sheetfile "hdmi-sd-card.kicad_sch")
		(attr smd)
		(fp_rect
			(start -0.925 -0.47)
			(end 0.925 0.47)
			(stroke
				(width 0.05)
				(type default)
			)
			(fill no)
			(layer "F.CrtYd")
		)
		(fp_line
			(start 0.504 0.248)
			(end -0.494 0.248)
			(stroke
				(width 0.15)
				(type solid)
			)
			(layer "F.Fab")
		)
		(fp_line
			(start 0.504 -0.25)
			(end 0.504 0.248)
			(stroke
				(width 0.15)
				(type solid)
			)
			(layer "F.Fab")
		)
		(fp_line
			(start -0.494 0.248)
			(end -0.494 -0.25)
			(stroke
				(width 0.15)
				(type solid)
			)
			(layer "F.Fab")
		)
		(fp_line
			(start -0.494 -0.25)
			(end 0.504 -0.25)
			(stroke
				(width 0.15)
				(type solid)
			)
			(layer "F.Fab")
		)
		(fp_text user "License: Apache-2.0"
			(at -0.939 5.799 180)
			(layer "F.Fab")
			(effects
				(font
					(size 0.7 0.7)
					(thickness 0.15)
				)
				(justify left bottom)
			)
		)
		(fp_text user "${REFERENCE}"
			(at -0.939 4.599 180)
			(layer "F.Fab")
			(effects
				(font
					(size 0.7 0.7)
					(thickness 0.15)
				)
				(justify left bottom)
			)
		)
		(fp_text user "Author: Antmicro"
			(at -0.939 3.399 180)
			(layer "F.Fab")
			(effects
				(font
					(size 0.7 0.7)
					(thickness 0.15)
				)
				(justify left bottom)
			)
		)
		(pad "1" smd roundrect
			(at -0.48 0 180)
			(size 0.59 0.64)
			(layers "F.Cu" "F.Mask" "F.Paste")
			(roundrect_rratio 0.25)
			(net 810 "/HDMI + SD Card/HDMI_VDD")
			(pintype "passive")
		)
		(pad "2" smd roundrect
			(at 0.48 0 180)
			(size 0.59 0.64)
			(layers "F.Cu" "F.Mask" "F.Paste")
			(roundrect_rratio 0.25)
			(net 1 "GND")
			(pintype "passive")
		)
	)
	(footprint "antmicro-footprints:C_0402_1005Metric"
		(layer "F.Cu")
		(at 222.98 180.74 90)
		(descr "Capacitor SMD 0402")
		(tags "capacitor SMD 0402")
		(property "Reference" "C208"
			(at -6.62 0.97 90)
			(layer "F.SilkS")
			(effects
				(font
					(size 0.7 0.7)
					(thickness 0.15)
				)
				(justify left bottom)
			)
		)
		(property "Value" "C_4u7_25V_0402"
			(at -1.022927 2.155213 90)
			(layer "F.Fab")
			(effects
				(font
					(size 0.7 0.7)
					(thickness 0.15)
				)
				(justify left bottom)
			)
		)
		(property "Datasheet" "https://www.murata.com/products/productdetail?partno=GRM155C61E475ME15%23"
			(at 0 0 90)
			(layer "F.Fab")
			(hide yes)
			(effects
				(font
					(size 1.27 1.27)
					(thickness 0.15)
				)
			)
		)
		(property "MPN" "GRM155C61E475ME15J"
			(at 0 0 90)
			(unlocked yes)
			(layer "F.Fab")
			(hide yes)
			(effects
				(font
					(size 1 1)
					(thickness 0.15)
				)
			)
		)
		(property "Manufacturer" "Murata"
			(at 0 0 90)
			(unlocked yes)
			(layer "F.Fab")
			(hide yes)
			(effects
				(font
					(size 1 1)
					(thickness 0.15)
				)
			)
		)
		(property "License" "Apache-2.0"
			(at 0 0 90)
			(unlocked yes)
			(layer "F.Fab")
			(hide yes)
			(effects
				(font
					(size 1 1)
					(thickness 0.15)
				)
			)
		)
		(property "Author" "Antmicro"
			(at 0 0 90)
			(unlocked yes)
			(layer "F.Fab")
			(hide yes)
			(effects
				(font
					(size 1 1)
					(thickness 0.15)
				)
			)
		)
		(property "Val" "4u7"
			(at 0 0 90)
			(unlocked yes)
			(layer "F.Fab")
			(hide yes)
			(effects
				(font
					(size 1 1)
					(thickness 0.15)
				)
			)
		)
		(property "Voltage" "25V"
			(at 0 0 90)
			(unlocked yes)
			(layer "F.Fab")
			(hide yes)
			(effects
				(font
					(size 1 1)
					(thickness 0.15)
				)
			)
		)
		(property "Dielectric" "X5S"
			(at 0 0 90)
			(unlocked yes)
			(layer "F.Fab")
			(hide yes)
			(effects
				(font
					(size 1 1)
					(thickness 0.15)
				)
			)
		)
		(sheetname "/Supply/DC-DC VCCINT/")
		(sheetfile "dc-dc-vccint.kicad_sch")
		(attr smd)
		(fp_rect
			(start -0.925 -0.47)
			(end 0.925 0.47)
			(stroke
				(width 0.05)
				(type default)
			)
			(fill no)
			(layer "F.CrtYd")
		)
		(fp_line
			(start 0.504 -0.25)
			(end 0.504 0.248)
			(stroke
				(width 0.15)
				(type solid)
			)
			(layer "F.Fab")
		)
		(fp_line
			(start -0.494 -0.25)
			(end 0.504 -0.25)
			(stroke
				(width 0.15)
				(type solid)
			)
			(layer "F.Fab")
		)
		(fp_line
			(start 0.504 0.248)
			(end -0.494 0.248)
			(stroke
				(width 0.15)
				(type solid)
			)
			(layer "F.Fab")
		)
		(fp_line
			(start -0.494 0.248)
			(end -0.494 -0.25)
			(stroke
				(width 0.15)
				(type solid)
			)
			(layer "F.Fab")
		)
		(fp_text user "License: Apache-2.0"
			(at -0.939 5.799 90)
			(layer "F.Fab")
			(effects
				(font
					(size 0.7 0.7)
					(thickness 0.15)
				)
				(justify left bottom)
			)
		)
		(fp_text user "${REFERENCE}"
			(at -0.939 4.599 90)
			(layer "F.Fab")
			(effects
				(font
					(size 0.7 0.7)
					(thickness 0.15)
				)
				(justify left bottom)
			)
		)
		(fp_text user "Author: Antmicro"
			(at -0.939 3.399 90)
			(layer "F.Fab")
			(effects
				(font
					(size 0.7 0.7)
					(thickness 0.15)
				)
				(justify left bottom)
			)
		)
		(pad "1" smd roundrect
			(at -0.48 0 90)
			(size 0.59 0.64)
			(layers "F.Cu" "F.Mask" "F.Paste")
			(roundrect_rratio 0.25)
			(net 1 "GND")
			(pintype "passive")
		)
		(pad "2" smd roundrect
			(at 0.48 0 90)
			(size 0.59 0.64)
			(layers "F.Cu" "F.Mask" "F.Paste")
			(roundrect_rratio 0.25)
			(net 163 "/Supply/DC-DC VCCINT/V_{CC}")
			(pintype "passive")
		)
	)
	(footprint "antmicro-footprints:R_0402_1005Metric"
		(layer "F.Cu")
		(at 126.681 168.3125 90)
		(descr "Resistor SMD 0402")
		(tags "resistor SMD 0402")
		(property "Reference" "R71"
			(at -3.15 0.619 90)
			(layer "F.SilkS")
			(effects
				(font
					(size 0.7 0.7)
					(thickness 0.15)
				)
				(justify left bottom)
			)
		)
		(property "Value" "R_64k9_0402"
			(at -1.011843 1.772047 90)
			(layer "F.Fab")
			(effects
				(font
					(size 0.7 0.7)
					(thickness 0.15)
				)
				(justify left bottom)
			)
		)
		(property "Datasheet" "https://www.bourns.com/docs/product-datasheets/cr.pdf"
			(at 0 0 90)
			(layer "F.Fab")
			(hide yes)
			(effects
				(font
					(size 1.27 1.27)
					(thickness 0.15)
				)
			)
		)
		(property "MPN" "CR0402-FX-6492GLF"
			(at 0 0 90)
			(unlocked yes)
			(layer "F.Fab")
			(hide yes)
			(effects
				(font
					(size 1 1)
					(thickness 0.15)
				)
			)
		)
		(property "Manufacturer" "Bourns"
			(at 0 0 90)
			(unlocked yes)
			(layer "F.Fab")
			(hide yes)
			(effects
				(font
					(size 1 1)
					(thickness 0.15)
				)
			)
		)
		(property "License" "Apache-2.0"
			(at 0 0 90)
			(unlocked yes)
			(layer "F.Fab")
			(hide yes)
			(effects
				(font
					(size 1 1)
					(thickness 0.15)
				)
			)
		)
		(property "Author" "Antmicro"
			(at 0 0 90)
			(unlocked yes)
			(layer "F.Fab")
			(hide yes)
			(effects
				(font
					(size 1 1)
					(thickness 0.15)
				)
			)
		)
		(property "Val" "64k9"
			(at 0 0 90)
			(unlocked yes)
			(layer "F.Fab")
			(hide yes)
			(effects
				(font
					(size 1 1)
					(thickness 0.15)
				)
			)
		)
		(property "Tolerance" "1%"
			(at 0 0 90)
			(unlocked yes)
			(layer "F.Fab")
			(hide yes)
			(effects
				(font
					(size 1 1)
					(thickness 0.15)
				)
			)
		)
		(sheetname "/HDMI + SD Card/")
		(sheetfile "hdmi-sd-card.kicad_sch")
		(attr smd exclude_from_bom dnp)
		(fp_rect
			(start -0.925 -0.47)
			(end 0.925 0.47)
			(stroke
				(width 0.05)
				(type default)
			)
			(fill no)
			(layer "F.CrtYd")
		)
		(fp_rect
			(start -0.5 -0.25)
			(end 0.5 0.25)
			(stroke
				(width 0.15)
				(type solid)
			)
			(fill no)
			(layer "F.Fab")
		)
		(fp_text user "${REFERENCE}"
			(at -0.95 3.168 90)
			(layer "F.Fab")
			(effects
				(font
					(size 0.7 0.7)
					(thickness 0.15)
				)
				(justify left bottom)
			)
		)
		(fp_text user "Author: Antmicro"
			(at -0.95 4.169 90)
			(layer "F.Fab")
			(effects
				(font
					(size 0.7 0.7)
					(thickness 0.15)
				)
				(justify left bottom)
			)
		)
		(fp_text user "License: Apache-2.0"
			(at -0.95 5.169 90)
			(layer "F.Fab")
			(effects
				(font
					(size 0.7 0.7)
					(thickness 0.15)
				)
				(justify left bottom)
			)
		)
		(pad "1" smd roundrect
			(at -0.48 0 90)
			(size 0.59 0.64)
			(layers "F.Cu" "F.Mask" "F.Paste")
			(roundrect_rratio 0.25)
			(net 1 "GND")
			(pintype "passive")
		)
		(pad "2" smd roundrect
			(at 0.48 0 90)
			(size 0.59 0.64)
			(layers "F.Cu" "F.Mask" "F.Paste")
			(roundrect_rratio 0.25)
			(net 707 "/HDMI + SD Card/SWAP{slash}POL")
			(pintype "passive")
		)
	)
	(footprint "antmicro-footprints:C_0402_1005Metric"
		(layer "F.Cu")
		(at 241.774499 174.27 90)
		(descr "Capacitor SMD 0402")
		(tags "capacitor SMD 0402")
		(property "Reference" "C199"
			(at -3.63 0.775501 90)
			(layer "F.SilkS")
			(effects
				(font
					(size 0.7 0.7)
					(thickness 0.15)
				)
				(justify left bottom)
			)
		)
		(property "Value" "C_100n_0402"
			(at -1.022927 2.155213 90)
			(layer "F.Fab")
			(effects
				(font
					(size 0.7 0.7)
					(thickness 0.15)
				)
				(justify left bottom)
			)
		)
		(property "Datasheet" "https://www.murata.com/products/productdetail?partno=GRM155R61H104KE14%23"
			(at 0 0 90)
			(layer "F.Fab")
			(hide yes)
			(effects
				(font
					(size 1.27 1.27)
					(thickness 0.15)
				)
			)
		)
		(property "Manufacturer" "Murata"
			(at 0 0 90)
			(unlocked yes)
			(layer "F.Fab")
			(hide yes)
			(effects
				(font
					(size 1 1)
					(thickness 0.15)
				)
			)
		)
		(property "MPN" "GRM155R61H104KE14D"
			(at 0 0 90)
			(unlocked yes)
			(layer "F.Fab")
			(hide yes)
			(effects
				(font
					(size 1 1)
					(thickness 0.15)
				)
			)
		)
		(property "Val" "100n"
			(at 0 0 90)
			(unlocked yes)
			(layer "F.Fab")
			(hide yes)
			(effects
				(font
					(size 1 1)
					(thickness 0.15)
				)
			)
		)
		(property "License" "Apache-2.0"
			(at 0 0 90)
			(unlocked yes)
			(layer "F.Fab")
			(hide yes)
			(effects
				(font
					(size 1 1)
					(thickness 0.15)
				)
			)
		)
		(property "Author" "Antmicro"
			(at 0 0 90)
			(unlocked yes)
			(layer "F.Fab")
			(hide yes)
			(effects
				(font
					(size 1 1)
					(thickness 0.15)
				)
			)
		)
		(property "Voltage" "50V"
			(at 0 0 90)
			(unlocked yes)
			(layer "F.Fab")
			(hide yes)
			(effects
				(font
					(size 1 1)
					(thickness 0.15)
				)
			)
		)
		(property "Dielectric" "X5R"
			(at 0 0 90)
			(unlocked yes)
			(layer "F.Fab")
			(hide yes)
			(effects
				(font
					(size 1 1)
					(thickness 0.15)
				)
			)
		)
		(sheetname "/Supply/DC-DC AUX, MGT/")
		(sheetfile "dc-dc-aux-mgt.kicad_sch")
		(attr smd)
		(fp_rect
			(start -0.925 -0.47)
			(end 0.925 0.47)
			(stroke
				(width 0.05)
				(type default)
			)
			(fill no)
			(layer "F.CrtYd")
		)
		(fp_line
			(start 0.504 -0.25)
			(end 0.504 0.248)
			(stroke
				(width 0.15)
				(type solid)
			)
			(layer "F.Fab")
		)
		(fp_line
			(start -0.494 -0.25)
			(end 0.504 -0.25)
			(stroke
				(width 0.15)
				(type solid)
			)
			(layer "F.Fab")
		)
		(fp_line
			(start 0.504 0.248)
			(end -0.494 0.248)
			(stroke
				(width 0.15)
				(type solid)
			)
			(layer "F.Fab")
		)
		(fp_line
			(start -0.494 0.248)
			(end -0.494 -0.25)
			(stroke
				(width 0.15)
				(type solid)
			)
			(layer "F.Fab")
		)
		(fp_text user "License: Apache-2.0"
			(at -0.939 5.799 90)
			(layer "F.Fab")
			(effects
				(font
					(size 0.7 0.7)
					(thickness 0.15)
				)
				(justify left bottom)
			)
		)
		(fp_text user "Author: Antmicro"
			(at -0.939 3.399 90)
			(layer "F.Fab")
			(effects
				(font
					(size 0.7 0.7)
					(thickness 0.15)
				)
				(justify left bottom)
			)
		)
		(fp_text user "${REFERENCE}"
			(at -0.939 4.599 90)
			(layer "F.Fab")
			(effects
				(font
					(size 0.7 0.7)
					(thickness 0.15)
				)
				(justify left bottom)
			)
		)
		(pad "1" smd roundrect
			(at -0.48 0 90)
			(size 0.59 0.64)
			(layers "F.Cu" "F.Mask" "F.Paste")
			(roundrect_rratio 0.25)
			(net 38 "+3V3_AON")
			(pintype "passive")
		)
		(pad "2" smd roundrect
			(at 0.48 0 90)
			(size 0.59 0.64)
			(layers "F.Cu" "F.Mask" "F.Paste")
			(roundrect_rratio 0.25)
			(net 1 "GND")
			(pintype "passive")
		)
	)
	(footprint "antmicro-footprints:R_0402_1005Metric"
		(layer "F.Cu")
		(at 119.15 154.61 180)
		(descr "Resistor SMD 0402")
		(tags "resistor SMD 0402")
		(property "Reference" "R31"
			(at -5.11 -0.38 0)
			(layer "F.SilkS")
			(effects
				(font
					(size 0.7 0.7)
					(thickness 0.15)
				)
				(justify right bottom)
			)
		)
		(property "Value" "R_49k9_0402"
			(at -1.011843 1.772047 0)
			(layer "F.Fab")
			(effects
				(font
					(size 0.7 0.7)
					(thickness 0.15)
				)
				(justify right bottom)
			)
		)
		(property "Datasheet" "https://www.bourns.com/docs/product-datasheets/cr.pdf"
			(at 0 0 180)
			(layer "F.Fab")
			(hide yes)
			(effects
				(font
					(size 1.27 1.27)
					(thickness 0.15)
				)
			)
		)
		(property "MPN" "CR0402-FX-4992GLF"
			(at 0 0 180)
			(unlocked yes)
			(layer "F.Fab")
			(hide yes)
			(effects
				(font
					(size 1 1)
					(thickness 0.15)
				)
			)
		)
		(property "Manufacturer" "Bourns"
			(at 0 0 180)
			(unlocked yes)
			(layer "F.Fab")
			(hide yes)
			(effects
				(font
					(size 1 1)
					(thickness 0.15)
				)
			)
		)
		(property "License" "Apache-2.0"
			(at 0 0 180)
			(unlocked yes)
			(layer "F.Fab")
			(hide yes)
			(effects
				(font
					(size 1 1)
					(thickness 0.15)
				)
			)
		)
		(property "Author" "Antmicro"
			(at 0 0 180)
			(unlocked yes)
			(layer "F.Fab")
			(hide yes)
			(effects
				(font
					(size 1 1)
					(thickness 0.15)
				)
			)
		)
		(property "Val" "49k9"
			(at 0 0 180)
			(unlocked yes)
			(layer "F.Fab")
			(hide yes)
			(effects
				(font
					(size 1 1)
					(thickness 0.15)
				)
			)
		)
		(property "Tolerance" "1%"
			(at 0 0 180)
			(unlocked yes)
			(layer "F.Fab")
			(hide yes)
			(effects
				(font
					(size 1 1)
					(thickness 0.15)
				)
			)
		)
		(sheetname "/HDMI + SD Card/")
		(sheetfile "hdmi-sd-card.kicad_sch")
		(attr smd)
		(fp_rect
			(start -0.925 -0.47)
			(end 0.925 0.47)
			(stroke
				(width 0.05)
				(type default)
			)
			(fill no)
			(layer "F.CrtYd")
		)
		(fp_rect
			(start -0.5 -0.25)
			(end 0.5 0.25)
			(stroke
				(width 0.15)
				(type solid)
			)
			(fill no)
			(layer "F.Fab")
		)
		(fp_text user "License: Apache-2.0"
			(at -0.95 5.169 180)
			(layer "F.Fab")
			(effects
				(font
					(size 0.7 0.7)
					(thickness 0.15)
				)
				(justify left bottom)
			)
		)
		(fp_text user "Author: Antmicro"
			(at -0.95 4.169 180)
			(layer "F.Fab")
			(effects
				(font
					(size 0.7 0.7)
					(thickness 0.15)
				)
				(justify left bottom)
			)
		)
		(fp_text user "${REFERENCE}"
			(at -0.95 3.168 180)
			(layer "F.Fab")
			(effects
				(font
					(size 0.7 0.7)
					(thickness 0.15)
				)
				(justify left bottom)
			)
		)
		(pad "1" smd roundrect
			(at -0.48 0 180)
			(size 0.59 0.64)
			(layers "F.Cu" "F.Mask" "F.Paste")
			(roundrect_rratio 0.25)
			(net 677 "Net-(L7-Pad2)")
			(pintype "passive")
		)
		(pad "2" smd roundrect
			(at 0.48 0 180)
			(size 0.59 0.64)
			(layers "F.Cu" "F.Mask" "F.Paste")
			(roundrect_rratio 0.25)
			(net 322 "Net-(C300-Pad2)")
			(pintype "passive")
		)
	)
)
